(kicad_pcb
	(version 20260206)
	(generator "pcbnew")
	(generator_version "10.0")
	(general
		(thickness 1.6)
		(legacy_teardrops no)
	)
	(paper "A4")
	(title_block
		(title "Bryce Canyon_SCC_16316-1_OCP.brd")
		(comment 1 "Bryce Canyon / footprints 318-325 of 1561")
	)
	(layers
		(0 "F.Cu" signal "TOP")
		(4 "In1.Cu" signal "L2GND")
		(6 "In2.Cu" signal "L3")
		(8 "In3.Cu" signal "L4VCC")
		(10 "In4.Cu" signal "L5VCC")
		(12 "In5.Cu" signal "L6")
		(14 "In6.Cu" signal "L7GND")
		(2 "B.Cu" signal "BOTTOM")
		(9 "F.Adhes" user "F.Adhesive")
		(11 "B.Adhes" user "B.Adhesive")
		(13 "F.Paste" user "Package Geometry/Pastemask Top")
		(15 "B.Paste" user "Package Geometry/Pastemask Bottom")
		(5 "F.SilkS" user "Ref Des/Silkscreen Top")
		(7 "B.SilkS" user "Ref Des/Silkscreen Bottom")
		(1 "F.Mask" user "Board Geometry/Soldermask Top")
		(3 "B.Mask" user "Board Geometry/Soldermask Bottom")
		(17 "Dwgs.User" user "User.Drawings")
		(19 "Cmts.User" user "User.Comments")
		(21 "Eco1.User" user "User.Eco1")
		(23 "Eco2.User" user "User.Eco2")
		(25 "Edge.Cuts" user "Board Geometry/Outline")
		(27 "Margin" user)
		(31 "F.CrtYd" user "Package Geometry/Place Bound Top")
		(29 "B.CrtYd" user "Package Geometry/Place Bound Bottom")
		(35 "F.Fab" user "Ref Des/Assembly Top")
		(33 "B.Fab" user "Ref Des/Assembly Bottom")
	)
	(footprint ""
		(layer "F.Cu")
		(at 35.8648 -49.7332 180)
		(property "Reference" "C527"
			(at 0 0 180)
			(layer "F.SilkS")
			(hide yes)
			(effects
				(font
					(size 1.27 1.27)
				)
			)
		)
		(property "Value" "SC10U16V5KX-7-GP-U"
			(at -0.0762 -6.1214 180)
			(unlocked yes)
			(layer "F.Fab")
			(hide yes)
			(effects
				(font
					(size 1.016 1.016)
					(thickness 0.1524)
				)
			)
		)
		(property "Device Type" "C805H58"
			(at -0.0762 -8.1534 180)
			(unlocked yes)
			(layer "F.Fab")
			(hide yes)
			(effects
				(font
					(size 1.016 1.016)
					(thickness 0.1524)
				)
			)
		)
		(duplicate_pad_numbers_are_jumpers no)
		(fp_line
			(start 0.635 0)
			(end -0.635 0)
			(stroke
				(width 0.508)
				(type default)
			)
			(layer "F.SilkS")
		)
		(fp_rect
			(start -0.9652 1.778)
			(end 0.9652 -1.778)
			(stroke
				(width 0)
				(type default)
			)
			(fill no)
			(layer "F.CrtYd")
		)
		(fp_poly
			(pts
				(xy -0.9652 -1.778) (xy 0.9652 -1.778) (xy 0.9652 1.778) (xy -0.9652 1.778)
			)
			(stroke
				(width 0)
				(type default)
			)
			(fill no)
			(layer "F.Fab")
		)
		(pad "1" smd rect
			(at 0 -0.9652 180)
			(size 1.397 1.143)
			(layers "F.Cu" "F.Mask" "F.Paste")
			(net "P12V_STBY_VIN_Q7")
		)
		(pad "2" smd rect
			(at 0 0.9652 180)
			(size 1.397 1.143)
			(layers "F.Cu" "F.Mask" "F.Paste")
			(net "GND")
		)
	)
	(footprint ""
		(layer "F.Cu")
		(at 194.437 -30.353 -90)
		(property "Reference" "TP71"
			(at 0 0 270)
			(layer "F.SilkS")
			(hide yes)
			(effects
				(font
					(size 1.27 1.27)
				)
			)
		)
		(property "Value" "TPAD28-2-GP"
			(at -0.0127 -1.6637 270)
			(unlocked yes)
			(layer "F.Fab")
			(hide yes)
			(effects
				(font
					(size 1.016 1.016)
					(thickness 0.1524)
				)
			)
		)
		(property "Device Type" "TPAD28"
			(at -0.0127 -3.1877 270)
			(unlocked yes)
			(layer "F.Fab")
			(hide yes)
			(effects
				(font
					(size 1.016 1.016)
					(thickness 0.1524)
				)
			)
		)
		(duplicate_pad_numbers_are_jumpers no)
		(fp_poly
			(pts
				(arc
					(start 0 -0.3556)
					(mid 0 0.3556)
					(end 0 -0.3556)
				)
			)
			(stroke
				(width 0)
				(type default)
			)
			(fill no)
			(layer "F.CrtYd")
		)
		(fp_poly
			(pts
				(arc
					(start 0 -0.6096)
					(mid 0 0.6096)
					(end 0 -0.6096)
				)
			)
			(stroke
				(width 0)
				(type default)
			)
			(fill no)
			(layer "F.Fab")
		)
		(pad "1" smd circle
			(at 0 0 270)
			(size 0.7112 0.7112)
			(layers "F.Cu" "F.Mask" "F.Paste")
			(net "IOC_GPIO_18")
		)
	)
	(footprint ""
		(layer "F.Cu")
		(at 8.4074 -53.8226 -90)
		(property "Reference" "C647"
			(at 0 0 270)
			(layer "F.SilkS")
			(hide yes)
			(effects
				(font
					(size 1.27 1.27)
				)
			)
		)
		(property "Value" "SCD1U16V2KX-3GP"
			(at 1.1811 -2.7051 270)
			(unlocked yes)
			(layer "F.Fab")
			(hide yes)
			(effects
				(font
					(size 1.016 1.016)
					(thickness 0.1524)
				)
			)
		)
		(property "Device Type" "C402H22"
			(at 1.1811 -4.2291 270)
			(unlocked yes)
			(layer "F.Fab")
			(hide yes)
			(effects
				(font
					(size 1.016 1.016)
					(thickness 0.1524)
				)
			)
		)
		(duplicate_pad_numbers_are_jumpers no)
		(fp_rect
			(start -0.4318 0.9525)
			(end 0.4318 -0.9525)
			(stroke
				(width 0)
				(type default)
			)
			(fill no)
			(layer "F.CrtYd")
		)
		(fp_rect
			(start -0.4318 0.9525)
			(end 0.4318 -0.9525)
			(stroke
				(width 0)
				(type default)
			)
			(fill no)
			(layer "F.Fab")
		)
		(pad "1" smd custom
			(at 0 -0.4445 270)
			(size 0.1524 0.1524)
			(layers "F.Cu" "F.Mask" "F.Paste")
			(net "MB0_CM_VOUT_R")
			(options
				(clearance outline)
				(anchor circle)
			)
			(primitives
				(gr_poly
					(pts
						(arc
							(start 0.3048 -0.2032)
							(mid 0.275042 -0.275042)
							(end 0.2032 -0.3048)
						)
						(arc
							(start -0.2032 -0.3048)
							(mid -0.275042 -0.275042)
							(end -0.3048 -0.2032)
						)
						(arc
							(start -0.3048 0.2032)
							(mid -0.275042 0.275042)
							(end -0.2032 0.3048)
						)
						(arc
							(start 0.2032 0.3048)
							(mid 0.275042 0.275042)
							(end 0.3048 0.2032)
						)
					)
					(width 0)
					(fill yes)
				)
			)
		)
		(pad "2" smd custom
			(at 0 0.4445 270)
			(size 0.1524 0.1524)
			(layers "F.Cu" "F.Mask" "F.Paste")
			(net "AGND_CURRENT_MON")
			(options
				(clearance outline)
				(anchor circle)
			)
			(primitives
				(gr_poly
					(pts
						(arc
							(start 0.3048 -0.2032)
							(mid 0.275042 -0.275042)
							(end 0.2032 -0.3048)
						)
						(arc
							(start -0.2032 -0.3048)
							(mid -0.275042 -0.275042)
							(end -0.3048 -0.2032)
						)
						(arc
							(start -0.3048 0.2032)
							(mid -0.275042 0.275042)
							(end -0.2032 0.3048)
						)
						(arc
							(start 0.2032 0.3048)
							(mid 0.275042 0.275042)
							(end 0.3048 0.2032)
						)
					)
					(width 0)
					(fill yes)
				)
			)
		)
	)
	(footprint ""
		(layer "F.Cu")
		(at 174.625 -95.885 90)
		(property "Reference" "C622"
			(at 0 0 90)
			(layer "F.SilkS")
			(hide yes)
			(effects
				(font
					(size 1.27 1.27)
				)
			)
		)
		(property "Value" "SC1U25V3KX-GP"
			(at 0 -2.8194 90)
			(unlocked yes)
			(layer "F.Fab")
			(hide yes)
			(effects
				(font
					(size 1.016 1.016)
					(thickness 0.1524)
				)
			)
		)
		(property "Device Type" "C603H36"
			(at 0 -4.3434 90)
			(unlocked yes)
			(layer "F.Fab")
			(hide yes)
			(effects
				(font
					(size 1.016 1.016)
					(thickness 0.1524)
				)
			)
		)
		(duplicate_pad_numbers_are_jumpers no)
		(fp_line
			(start 0.508 0)
			(end -0.508 0)
			(stroke
				(width 0.2032)
				(type default)
			)
			(layer "F.SilkS")
		)
		(fp_rect
			(start -0.5842 1.3335)
			(end 0.5842 -1.3335)
			(stroke
				(width 0)
				(type default)
			)
			(fill no)
			(layer "F.CrtYd")
		)
		(fp_rect
			(start -0.5842 1.3335)
			(end 0.5842 -1.3335)
			(stroke
				(width 0)
				(type default)
			)
			(fill no)
			(layer "F.Fab")
		)
		(pad "1" smd custom
			(at 0 -0.762 90)
			(size 0.2159 0.2159)
			(layers "F.Cu" "F.Mask" "F.Paste")
			(net "VT235_VDDL")
			(options
				(clearance outline)
				(anchor circle)
			)
			(primitives
				(gr_poly
					(pts
						(arc
							(start -0.3302 -0.4318)
							(mid -0.402042 -0.402042)
							(end -0.4318 -0.3302)
						)
						(arc
							(start -0.4318 0.3302)
							(mid -0.402042 0.402042)
							(end -0.3302 0.4318)
						)
						(arc
							(start 0.3302 0.4318)
							(mid 0.402042 0.402042)
							(end 0.4318 0.3302)
						)
						(arc
							(start 0.4318 -0.3302)
							(mid 0.402042 -0.402042)
							(end 0.3302 -0.4318)
						)
					)
					(width 0)
					(fill yes)
				)
			)
		)
		(pad "2" smd custom
			(at 0 0.762 90)
			(size 0.2159 0.2159)
			(layers "F.Cu" "F.Mask" "F.Paste")
			(net "GND")
			(options
				(clearance outline)
				(anchor circle)
			)
			(primitives
				(gr_poly
					(pts
						(arc
							(start -0.3302 -0.4318)
							(mid -0.402042 -0.402042)
							(end -0.4318 -0.3302)
						)
						(arc
							(start -0.4318 0.3302)
							(mid -0.402042 0.402042)
							(end -0.3302 0.4318)
						)
						(arc
							(start 0.3302 0.4318)
							(mid 0.402042 0.402042)
							(end 0.4318 0.3302)
						)
						(arc
							(start 0.4318 -0.3302)
							(mid 0.402042 -0.402042)
							(end 0.3302 -0.4318)
						)
					)
					(width 0)
					(fill yes)
				)
			)
		)
	)
	(footprint ""
		(layer "F.Cu")
		(at 72.451214 -70.758304 90)
		(property "Reference" "R439"
			(at 0 0 90)
			(layer "F.SilkS")
			(hide yes)
			(effects
				(font
					(size 1.27 1.27)
				)
			)
		)
		(property "Value" "200KR2F-L-GP"
			(at 0.064008 -3.993896 90)
			(unlocked yes)
			(layer "F.Fab")
			(hide yes)
			(effects
				(font
					(size 1.016 1.016)
					(thickness 0.1524)
				)
			)
		)
		(property "Device Type" "R402H16"
			(at 0.064008 -5.517896 90)
			(unlocked yes)
			(layer "F.Fab")
			(hide yes)
			(effects
				(font
					(size 1.016 1.016)
					(thickness 0.1524)
				)
			)
		)
		(duplicate_pad_numbers_are_jumpers no)
		(fp_line
			(start 0.508 -0.9398)
			(end -0.508 -0.9398)
			(stroke
				(width 0.1524)
				(type default)
			)
			(layer "F.SilkS")
		)
		(fp_line
			(start -0.508 -0.9398)
			(end -0.508 0.9398)
			(stroke
				(width 0.1524)
				(type default)
			)
			(layer "F.SilkS")
		)
		(fp_rect
			(start -0.508 0.9398)
			(end 0.508 -0.9398)
			(stroke
				(width 0)
				(type default)
			)
			(fill no)
			(layer "F.CrtYd")
		)
		(fp_rect
			(start -0.508 0.9398)
			(end 0.508 -0.9398)
			(stroke
				(width 0)
				(type default)
			)
			(fill no)
			(layer "F.Fab")
		)
		(pad "1" smd custom
			(at 0 -0.4445 90)
			(size 0.1397 0.1397)
			(layers "F.Cu" "F.Mask" "F.Paste")
			(net "LS_EN_U39")
			(options
				(clearance outline)
				(anchor circle)
			)
			(primitives
				(gr_poly
					(pts
						(arc
							(start -0.1778 -0.2794)
							(mid -0.249642 -0.249642)
							(end -0.2794 -0.1778)
						)
						(arc
							(start -0.2794 0.1778)
							(mid -0.249642 0.249642)
							(end -0.1778 0.2794)
						)
						(arc
							(start 0.1778 0.2794)
							(mid 0.249642 0.249642)
							(end 0.2794 0.1778)
						)
						(arc
							(start 0.2794 -0.1778)
							(mid 0.249642 -0.249642)
							(end 0.1778 -0.2794)
						)
					)
					(width 0)
					(fill yes)
				)
			)
		)
		(pad "2" smd custom
			(at 0 0.4445 90)
			(size 0.1397 0.1397)
			(layers "F.Cu" "F.Mask" "F.Paste")
			(net "P0V9_PG")
			(options
				(clearance outline)
				(anchor circle)
			)
			(primitives
				(gr_poly
					(pts
						(arc
							(start -0.1778 -0.2794)
							(mid -0.249642 -0.249642)
							(end -0.2794 -0.1778)
						)
						(arc
							(start -0.2794 0.1778)
							(mid -0.249642 0.249642)
							(end -0.1778 0.2794)
						)
						(arc
							(start 0.1778 0.2794)
							(mid 0.249642 0.249642)
							(end 0.2794 0.1778)
						)
						(arc
							(start 0.2794 -0.1778)
							(mid 0.249642 -0.249642)
							(end 0.1778 -0.2794)
						)
					)
					(width 0)
					(fill yes)
				)
			)
		)
	)
	(footprint ""
		(layer "F.Cu")
		(at 75.311 -51.5874 180)
		(property "Reference" "C275"
			(at 0 0 180)
			(layer "F.SilkS")
			(hide yes)
			(effects
				(font
					(size 1.27 1.27)
				)
			)
		)
		(property "Value" "SC22U6D3V3MX-9-GP-U"
			(at 0 -2.8194 180)
			(unlocked yes)
			(layer "F.Fab")
			(hide yes)
			(effects
				(font
					(size 1.016 1.016)
					(thickness 0.1524)
				)
			)
		)
		(property "Device Type" "C603H40"
			(at 0 -4.3434 180)
			(unlocked yes)
			(layer "F.Fab")
			(hide yes)
			(effects
				(font
					(size 1.016 1.016)
					(thickness 0.1524)
				)
			)
		)
		(duplicate_pad_numbers_are_jumpers no)
		(fp_line
			(start 0.508 0)
			(end -0.508 0)
			(stroke
				(width 0.2032)
				(type default)
			)
			(layer "F.SilkS")
		)
		(fp_rect
			(start -0.5842 1.3335)
			(end 0.5842 -1.3335)
			(stroke
				(width 0)
				(type default)
			)
			(fill no)
			(layer "F.CrtYd")
		)
		(fp_rect
			(start -0.5842 1.3335)
			(end 0.5842 -1.3335)
			(stroke
				(width 0)
				(type default)
			)
			(fill no)
			(layer "F.Fab")
		)
		(pad "1" smd custom
			(at 0 -0.762 180)
			(size 0.2159 0.2159)
			(layers "F.Cu" "F.Mask" "F.Paste")
			(net "GB_VDDA")
			(options
				(clearance outline)
				(anchor circle)
			)
			(primitives
				(gr_poly
					(pts
						(arc
							(start -0.3302 -0.4318)
							(mid -0.402042 -0.402042)
							(end -0.4318 -0.3302)
						)
						(arc
							(start -0.4318 0.3302)
							(mid -0.402042 0.402042)
							(end -0.3302 0.4318)
						)
						(arc
							(start 0.3302 0.4318)
							(mid 0.402042 0.402042)
							(end 0.4318 0.3302)
						)
						(arc
							(start 0.4318 -0.3302)
							(mid 0.402042 -0.402042)
							(end 0.3302 -0.4318)
						)
					)
					(width 0)
					(fill yes)
				)
			)
		)
		(pad "2" smd custom
			(at 0 0.762 180)
			(size 0.2159 0.2159)
			(layers "F.Cu" "F.Mask" "F.Paste")
			(net "GND")
			(options
				(clearance outline)
				(anchor circle)
			)
			(primitives
				(gr_poly
					(pts
						(arc
							(start -0.3302 -0.4318)
							(mid -0.402042 -0.402042)
							(end -0.4318 -0.3302)
						)
						(arc
							(start -0.4318 0.3302)
							(mid -0.402042 0.402042)
							(end -0.3302 0.4318)
						)
						(arc
							(start 0.3302 0.4318)
							(mid 0.402042 0.402042)
							(end 0.4318 0.3302)
						)
						(arc
							(start 0.4318 -0.3302)
							(mid 0.402042 -0.402042)
							(end 0.3302 -0.4318)
						)
					)
					(width 0)
					(fill yes)
				)
			)
		)
	)
	(footprint ""
		(layer "F.Cu")
		(at 191.035432 -71.161656 -90)
		(property "Reference" "C508"
			(at 0 0 270)
			(layer "F.SilkS")
			(hide yes)
			(effects
				(font
					(size 1.27 1.27)
				)
			)
		)
		(property "Value" "SCD1U16V2KX-3GP"
			(at 1.1811 -2.7051 270)
			(unlocked yes)
			(layer "F.Fab")
			(hide yes)
			(effects
				(font
					(size 1.016 1.016)
					(thickness 0.1524)
				)
			)
		)
		(property "Device Type" "C402H22"
			(at 1.1811 -4.2291 270)
			(unlocked yes)
			(layer "F.Fab")
			(hide yes)
			(effects
				(font
					(size 1.016 1.016)
					(thickness 0.1524)
				)
			)
		)
		(duplicate_pad_numbers_are_jumpers no)
		(fp_rect
			(start -0.4318 0.9525)
			(end 0.4318 -0.9525)
			(stroke
				(width 0)
				(type default)
			)
			(fill no)
			(layer "F.CrtYd")
		)
		(fp_rect
			(start -0.4318 0.9525)
			(end 0.4318 -0.9525)
			(stroke
				(width 0)
				(type default)
			)
			(fill no)
			(layer "F.Fab")
		)
		(pad "1" smd custom
			(at 0 -0.4445 270)
			(size 0.1524 0.1524)
			(layers "F.Cu" "F.Mask" "F.Paste")
			(net "P3V3")
			(options
				(clearance outline)
				(anchor circle)
			)
			(primitives
				(gr_poly
					(pts
						(arc
							(start 0.3048 -0.2032)
							(mid 0.275042 -0.275042)
							(end 0.2032 -0.3048)
						)
						(arc
							(start -0.2032 -0.3048)
							(mid -0.275042 -0.275042)
							(end -0.3048 -0.2032)
						)
						(arc
							(start -0.3048 0.2032)
							(mid -0.275042 0.275042)
							(end -0.2032 0.3048)
						)
						(arc
							(start 0.2032 0.3048)
							(mid 0.275042 0.275042)
							(end 0.3048 0.2032)
						)
					)
					(width 0)
					(fill yes)
				)
			)
		)
		(pad "2" smd custom
			(at 0 0.4445 270)
			(size 0.1524 0.1524)
			(layers "F.Cu" "F.Mask" "F.Paste")
			(net "GND")
			(options
				(clearance outline)
				(anchor circle)
			)
			(primitives
				(gr_poly
					(pts
						(arc
							(start 0.3048 -0.2032)
							(mid 0.275042 -0.275042)
							(end 0.2032 -0.3048)
						)
						(arc
							(start -0.2032 -0.3048)
							(mid -0.275042 -0.275042)
							(end -0.3048 -0.2032)
						)
						(arc
							(start -0.3048 0.2032)
							(mid -0.275042 0.275042)
							(end -0.2032 0.3048)
						)
						(arc
							(start 0.2032 0.3048)
							(mid 0.275042 0.275042)
							(end 0.3048 0.2032)
						)
					)
					(width 0)
					(fill yes)
				)
			)
		)
	)
	(footprint ""
		(layer "F.Cu")
		(at 18.3896 -85.852 -90)
		(property "Reference" "C541"
			(at 0 0 270)
			(layer "F.SilkS")
			(hide yes)
			(effects
				(font
					(size 1.27 1.27)
				)
			)
		)
		(property "Value" "SCD1U16V2KX-3GP"
			(at 1.1811 -2.7051 270)
			(unlocked yes)
			(layer "F.Fab")
			(hide yes)
			(effects
				(font
					(size 1.016 1.016)
					(thickness 0.1524)
				)
			)
		)
		(property "Device Type" "C402H22"
			(at 1.1811 -4.2291 270)
			(unlocked yes)
			(layer "F.Fab")
			(hide yes)
			(effects
				(font
					(size 1.016 1.016)
					(thickness 0.1524)
				)
			)
		)
		(duplicate_pad_numbers_are_jumpers no)
		(fp_rect
			(start -0.4318 0.9525)
			(end 0.4318 -0.9525)
			(stroke
				(width 0)
				(type default)
			)
			(fill no)
			(layer "F.CrtYd")
		)
		(fp_rect
			(start -0.4318 0.9525)
			(end 0.4318 -0.9525)
			(stroke
				(width 0)
				(type default)
			)
			(fill no)
			(layer "F.Fab")
		)
		(pad "1" smd custom
			(at 0 -0.4445 270)
			(size 0.1524 0.1524)
			(layers "F.Cu" "F.Mask" "F.Paste")
			(net "P1V8_E")
			(options
				(clearance outline)
				(anchor circle)
			)
			(primitives
				(gr_poly
					(pts
						(arc
							(start 0.3048 -0.2032)
							(mid 0.275042 -0.275042)
							(end 0.2032 -0.3048)
						)
						(arc
							(start -0.2032 -0.3048)
							(mid -0.275042 -0.275042)
							(end -0.3048 -0.2032)
						)
						(arc
							(start -0.3048 0.2032)
							(mid -0.275042 0.275042)
							(end -0.2032 0.3048)
						)
						(arc
							(start 0.2032 0.3048)
							(mid 0.275042 0.275042)
							(end 0.3048 0.2032)
						)
					)
					(width 0)
					(fill yes)
				)
			)
		)
		(pad "2" smd custom
			(at 0 0.4445 270)
			(size 0.1524 0.1524)
			(layers "F.Cu" "F.Mask" "F.Paste")
			(net "GND")
			(options
				(clearance outline)
				(anchor circle)
			)
			(primitives
				(gr_poly
					(pts
						(arc
							(start 0.3048 -0.2032)
							(mid 0.275042 -0.275042)
							(end 0.2032 -0.3048)
						)
						(arc
							(start -0.2032 -0.3048)
							(mid -0.275042 -0.275042)
							(end -0.3048 -0.2032)
						)
						(arc
							(start -0.3048 0.2032)
							(mid -0.275042 0.275042)
							(end -0.2032 0.3048)
						)
						(arc
							(start 0.2032 0.3048)
							(mid 0.275042 0.275042)
							(end 0.3048 0.2032)
						)
					)
					(width 0)
					(fill yes)
				)
			)
		)
	)
)
